(kicad_pcb
	(version 20260206)
	(generator "pcbnew")
	(generator_version "10.0")
	(general
		(thickness 1.6)
		(legacy_teardrops no)
	)
	(paper "A4")
	(title_block
		(title "03242023_DA0F0TMBIJ0_F0T_Motherboard_J_brd_V01_OCP.brd")
		(comment 1 "Grand Teton / footprints 456-460 of 6105")
	)
	(layers
		(0 "F.Cu" signal "TOP")
		(4 "In1.Cu" signal "GND")
		(6 "In2.Cu" signal "IN1")
		(8 "In3.Cu" signal "GND1")
		(10 "In4.Cu" signal "IN2")
		(12 "In5.Cu" signal "GND2")
		(14 "In6.Cu" signal "IN3")
		(16 "In7.Cu" signal "GND3")
		(18 "In8.Cu" signal "VCC")
		(20 "In9.Cu" signal "VCC1")
		(22 "In10.Cu" signal "GND4")
		(24 "In11.Cu" signal "IN4")
		(26 "In12.Cu" signal "GND5")
		(28 "In13.Cu" signal "IN5")
		(30 "In14.Cu" signal "GND6")
		(32 "In15.Cu" signal "IN6")
		(34 "In16.Cu" signal "GND7")
		(2 "B.Cu" signal "BOTTOM")
		(9 "F.Adhes" user "F.Adhesive")
		(11 "B.Adhes" user "B.Adhesive")
		(13 "F.Paste" user "Package Geometry/Pastemask Top")
		(15 "B.Paste" user "Package Geometry/Pastemask Bottom")
		(5 "F.SilkS" user "Ref Des/Silkscreen Top")
		(7 "B.SilkS" user "Ref Des/Silkscreen Bottom")
		(1 "F.Mask" user "Board Geometry/Soldermask Top")
		(3 "B.Mask" user "Board Geometry/Soldermask Bottom")
		(17 "Dwgs.User" user "User.Drawings")
		(19 "Cmts.User" user "User.Comments")
		(21 "Eco1.User" user "User.Eco1")
		(23 "Eco2.User" user "User.Eco2")
		(25 "Edge.Cuts" user "Board Geometry/Outline")
		(27 "Margin" user)
		(31 "F.CrtYd" user "Package Geometry/Place Bound Top")
		(29 "B.CrtYd" user "Package Geometry/Place Bound Bottom")
		(35 "F.Fab" user "Ref Des/Assembly Top")
		(33 "B.Fab" user "Ref Des/Assembly Bottom")
	)
	(footprint ""
		(layer "F.Cu")
		(at 61.475366 -174.230792)
		(property "Reference" "PL20"
			(at -6.598666 -4.515358 0)
			(unlocked yes)
			(layer "F.SilkS")
			(effects
				(font
					(size 0.7874 0.5842)
					(thickness 0.1524)
				)
				(justify left)
			)
		)
		(property "Value" ""
			(at 0 0 0)
			(layer "F.Fab")
			(effects
				(font
					(size 1.27 1.27)
				)
			)
		)
		(duplicate_pad_numbers_are_jumpers no)
		(fp_line
			(start -4.800092 -3.199892)
			(end 4.800092 -3.199892)
			(stroke
				(width 0.1524)
				(type default)
			)
			(layer "F.SilkS")
		)
		(fp_line
			(start -4.800092 -1.6891)
			(end -4.800092 -3.199892)
			(stroke
				(width 0.1524)
				(type default)
			)
			(layer "F.SilkS")
		)
		(fp_line
			(start -4.800092 3.199892)
			(end -4.800092 1.6891)
			(stroke
				(width 0.1524)
				(type default)
			)
			(layer "F.SilkS")
		)
		(fp_line
			(start 4.800092 -3.199892)
			(end 4.800092 -1.6891)
			(stroke
				(width 0.1524)
				(type default)
			)
			(layer "F.SilkS")
		)
		(fp_line
			(start 4.800092 1.6891)
			(end 4.800092 3.199892)
			(stroke
				(width 0.1524)
				(type default)
			)
			(layer "F.SilkS")
		)
		(fp_line
			(start 4.800092 3.199892)
			(end -4.800092 3.199892)
			(stroke
				(width 0.1524)
				(type default)
			)
			(layer "F.SilkS")
		)
		(fp_line
			(start -4.800092 -3.199892)
			(end 4.800092 -3.199892)
			(stroke
				(width 0.1)
				(type default)
			)
			(layer "F.Fab")
		)
		(fp_line
			(start -4.800092 3.199892)
			(end -4.800092 -3.199892)
			(stroke
				(width 0.1)
				(type default)
			)
			(layer "F.Fab")
		)
		(fp_line
			(start 4.800092 -3.199892)
			(end 4.800092 3.199892)
			(stroke
				(width 0.1)
				(type default)
			)
			(layer "F.Fab")
		)
		(fp_line
			(start 4.800092 3.199892)
			(end -4.800092 3.199892)
			(stroke
				(width 0.1)
				(type default)
			)
			(layer "F.Fab")
		)
		(pad "1" smd rect
			(at -3.350006 0 90)
			(size 3.0988 3.2004)
			(layers "F.Cu" "F.Mask" "F.Paste")
			(net "SW_PVCCFA_EHV_CPU1_SW1")
		)
		(pad "2" smd rect
			(at 3.350006 0 90)
			(size 3.0988 3.2004)
			(layers "F.Cu" "F.Mask" "F.Paste")
			(net "PVCCFA_EHV_CPU1")
		)
	)
	(footprint ""
		(layer "F.Cu")
		(at 51.593496 -113.72977)
		(property "Reference" "R3723"
			(at 0 0 0)
			(layer "F.SilkS")
			(hide yes)
			(effects
				(font
					(size 1.27 1.27)
				)
			)
		)
		(property "Value" ""
			(at 0 0 0)
			(layer "F.Fab")
			(effects
				(font
					(size 1.27 1.27)
				)
			)
		)
		(duplicate_pad_numbers_are_jumpers no)
		(fp_line
			(start -0.7874 -0.4064)
			(end 0.7874 -0.4064)
			(stroke
				(width 0.1524)
				(type default)
			)
			(layer "F.SilkS")
		)
		(fp_line
			(start -0.7874 0.4064)
			(end -0.7874 -0.4064)
			(stroke
				(width 0.1524)
				(type default)
			)
			(layer "F.SilkS")
		)
		(fp_line
			(start 0.7874 -0.4064)
			(end 0.7874 0.4064)
			(stroke
				(width 0.1524)
				(type default)
			)
			(layer "F.SilkS")
		)
		(fp_line
			(start 0.7874 0.4064)
			(end -0.7874 0.4064)
			(stroke
				(width 0.1524)
				(type default)
			)
			(layer "F.SilkS")
		)
		(fp_line
			(start -0.67945 -0.305054)
			(end -0.12065 -0.305054)
			(stroke
				(width 0.1)
				(type default)
			)
			(layer "F.Fab")
		)
		(fp_line
			(start -0.67945 0.3048)
			(end -0.67945 -0.305054)
			(stroke
				(width 0.1)
				(type default)
			)
			(layer "F.Fab")
		)
		(fp_line
			(start -0.12065 -0.305054)
			(end -0.12065 -0.2794)
			(stroke
				(width 0.1)
				(type default)
			)
			(layer "F.Fab")
		)
		(fp_line
			(start -0.12065 -0.2794)
			(end 0.12065 -0.2794)
			(stroke
				(width 0.1)
				(type default)
			)
			(layer "F.Fab")
		)
		(fp_line
			(start -0.12065 0.2794)
			(end -0.12065 0.3048)
			(stroke
				(width 0.1)
				(type default)
			)
			(layer "F.Fab")
		)
		(fp_line
			(start -0.12065 0.3048)
			(end -0.67945 0.3048)
			(stroke
				(width 0.1)
				(type default)
			)
			(layer "F.Fab")
		)
		(fp_line
			(start 0.120396 0.2794)
			(end -0.12065 0.2794)
			(stroke
				(width 0.1)
				(type default)
			)
			(layer "F.Fab")
		)
		(fp_line
			(start 0.120396 0.3048)
			(end 0.120396 0.2794)
			(stroke
				(width 0.1)
				(type default)
			)
			(layer "F.Fab")
		)
		(fp_line
			(start 0.12065 -0.3048)
			(end 0.67945 -0.3048)
			(stroke
				(width 0.1)
				(type default)
			)
			(layer "F.Fab")
		)
		(fp_line
			(start 0.12065 -0.2794)
			(end 0.12065 -0.3048)
			(stroke
				(width 0.1)
				(type default)
			)
			(layer "F.Fab")
		)
		(fp_line
			(start 0.67945 -0.3048)
			(end 0.67945 0.3048)
			(stroke
				(width 0.1)
				(type default)
			)
			(layer "F.Fab")
		)
		(fp_line
			(start 0.67945 0.3048)
			(end 0.120396 0.3048)
			(stroke
				(width 0.1)
				(type default)
			)
			(layer "F.Fab")
		)
		(pad "1" smd circle
			(at -0.40005 0)
			(size 0 0)
			(layers "F.Cu" "F.Mask" "F.Paste")
			(net "P3V3_AUX")
		)
		(pad "2" smd circle
			(at 0.40005 0)
			(size 0 0)
			(layers "F.Cu" "F.Mask" "F.Paste")
			(net "SMB_VR_3V3AUX_SCL")
		)
	)
	(footprint ""
		(layer "F.Cu")
		(at 182.58282 -419.47338 -90)
		(property "Reference" "R4796"
			(at 0 0 270)
			(layer "F.SilkS")
			(hide yes)
			(effects
				(font
					(size 1.27 1.27)
				)
			)
		)
		(property "Value" ""
			(at 0 0 270)
			(layer "F.Fab")
			(effects
				(font
					(size 1.27 1.27)
				)
			)
		)
		(duplicate_pad_numbers_are_jumpers no)
		(fp_line
			(start -0.7874 0.4064)
			(end -0.7874 -0.4064)
			(stroke
				(width 0.1524)
				(type default)
			)
			(layer "F.SilkS")
		)
		(fp_line
			(start 0.7874 0.4064)
			(end -0.7874 0.4064)
			(stroke
				(width 0.1524)
				(type default)
			)
			(layer "F.SilkS")
		)
		(fp_line
			(start -0.7874 -0.4064)
			(end 0.7874 -0.4064)
			(stroke
				(width 0.1524)
				(type default)
			)
			(layer "F.SilkS")
		)
		(fp_line
			(start 0.7874 -0.4064)
			(end 0.7874 0.4064)
			(stroke
				(width 0.1524)
				(type default)
			)
			(layer "F.SilkS")
		)
		(fp_line
			(start -0.67945 0.3048)
			(end -0.67945 -0.305054)
			(stroke
				(width 0.1)
				(type default)
			)
			(layer "F.Fab")
		)
		(fp_line
			(start -0.12065 0.3048)
			(end -0.67945 0.3048)
			(stroke
				(width 0.1)
				(type default)
			)
			(layer "F.Fab")
		)
		(fp_line
			(start 0.120396 0.3048)
			(end 0.120396 0.2794)
			(stroke
				(width 0.1)
				(type default)
			)
			(layer "F.Fab")
		)
		(fp_line
			(start 0.67945 0.3048)
			(end 0.120396 0.3048)
			(stroke
				(width 0.1)
				(type default)
			)
			(layer "F.Fab")
		)
		(fp_line
			(start -0.12065 0.2794)
			(end -0.12065 0.3048)
			(stroke
				(width 0.1)
				(type default)
			)
			(layer "F.Fab")
		)
		(fp_line
			(start 0.120396 0.2794)
			(end -0.12065 0.2794)
			(stroke
				(width 0.1)
				(type default)
			)
			(layer "F.Fab")
		)
		(fp_line
			(start -0.12065 -0.2794)
			(end 0.12065 -0.2794)
			(stroke
				(width 0.1)
				(type default)
			)
			(layer "F.Fab")
		)
		(fp_line
			(start 0.12065 -0.2794)
			(end 0.12065 -0.3048)
			(stroke
				(width 0.1)
				(type default)
			)
			(layer "F.Fab")
		)
		(fp_line
			(start 0.12065 -0.3048)
			(end 0.67945 -0.3048)
			(stroke
				(width 0.1)
				(type default)
			)
			(layer "F.Fab")
		)
		(fp_line
			(start 0.67945 -0.3048)
			(end 0.67945 0.3048)
			(stroke
				(width 0.1)
				(type default)
			)
			(layer "F.Fab")
		)
		(fp_line
			(start -0.67945 -0.305054)
			(end -0.12065 -0.305054)
			(stroke
				(width 0.1)
				(type default)
			)
			(layer "F.Fab")
		)
		(fp_line
			(start -0.12065 -0.305054)
			(end -0.12065 -0.2794)
			(stroke
				(width 0.1)
				(type default)
			)
			(layer "F.Fab")
		)
		(pad "1" smd circle
			(at -0.40005 0 270)
			(size 0 0)
			(layers "F.Cu" "F.Mask" "F.Paste")
			(net "HSC_OC_VOL")
		)
		(pad "2" smd circle
			(at 0.40005 0 270)
			(size 0 0)
			(layers "F.Cu" "F.Mask" "F.Paste")
			(net "GND")
		)
	)
	(footprint ""
		(layer "F.Cu")
		(at 68.212462 -39.421562)
		(property "Reference" "R3609"
			(at 0 0 0)
			(layer "F.SilkS")
			(hide yes)
			(effects
				(font
					(size 1.27 1.27)
				)
			)
		)
		(property "Value" ""
			(at 0 0 0)
			(layer "F.Fab")
			(effects
				(font
					(size 1.27 1.27)
				)
			)
		)
		(duplicate_pad_numbers_are_jumpers no)
		(fp_line
			(start -0.7874 -0.4064)
			(end 0.7874 -0.4064)
			(stroke
				(width 0.1524)
				(type default)
			)
			(layer "F.SilkS")
		)
		(fp_line
			(start -0.7874 0.4064)
			(end -0.7874 -0.4064)
			(stroke
				(width 0.1524)
				(type default)
			)
			(layer "F.SilkS")
		)
		(fp_line
			(start 0.7874 -0.4064)
			(end 0.7874 0.4064)
			(stroke
				(width 0.1524)
				(type default)
			)
			(layer "F.SilkS")
		)
		(fp_line
			(start 0.7874 0.4064)
			(end -0.7874 0.4064)
			(stroke
				(width 0.1524)
				(type default)
			)
			(layer "F.SilkS")
		)
		(fp_line
			(start -0.67945 -0.305054)
			(end -0.12065 -0.305054)
			(stroke
				(width 0.1)
				(type default)
			)
			(layer "F.Fab")
		)
		(fp_line
			(start -0.67945 0.3048)
			(end -0.67945 -0.305054)
			(stroke
				(width 0.1)
				(type default)
			)
			(layer "F.Fab")
		)
		(fp_line
			(start -0.12065 -0.305054)
			(end -0.12065 -0.2794)
			(stroke
				(width 0.1)
				(type default)
			)
			(layer "F.Fab")
		)
		(fp_line
			(start -0.12065 -0.2794)
			(end 0.12065 -0.2794)
			(stroke
				(width 0.1)
				(type default)
			)
			(layer "F.Fab")
		)
		(fp_line
			(start -0.12065 0.2794)
			(end -0.12065 0.3048)
			(stroke
				(width 0.1)
				(type default)
			)
			(layer "F.Fab")
		)
		(fp_line
			(start -0.12065 0.3048)
			(end -0.67945 0.3048)
			(stroke
				(width 0.1)
				(type default)
			)
			(layer "F.Fab")
		)
		(fp_line
			(start 0.120396 0.2794)
			(end -0.12065 0.2794)
			(stroke
				(width 0.1)
				(type default)
			)
			(layer "F.Fab")
		)
		(fp_line
			(start 0.120396 0.3048)
			(end 0.120396 0.2794)
			(stroke
				(width 0.1)
				(type default)
			)
			(layer "F.Fab")
		)
		(fp_line
			(start 0.12065 -0.3048)
			(end 0.67945 -0.3048)
			(stroke
				(width 0.1)
				(type default)
			)
			(layer "F.Fab")
		)
		(fp_line
			(start 0.12065 -0.2794)
			(end 0.12065 -0.3048)
			(stroke
				(width 0.1)
				(type default)
			)
			(layer "F.Fab")
		)
		(fp_line
			(start 0.67945 -0.3048)
			(end 0.67945 0.3048)
			(stroke
				(width 0.1)
				(type default)
			)
			(layer "F.Fab")
		)
		(fp_line
			(start 0.67945 0.3048)
			(end 0.120396 0.3048)
			(stroke
				(width 0.1)
				(type default)
			)
			(layer "F.Fab")
		)
		(pad "1" smd circle
			(at -0.40005 0)
			(size 0 0)
			(layers "F.Cu" "F.Mask" "F.Paste")
			(net "GND")
		)
		(pad "2" smd circle
			(at 0.40005 0)
			(size 0 0)
			(layers "F.Cu" "F.Mask" "F.Paste")
			(net "INA230_3_A0")
		)
	)
	(footprint ""
		(layer "F.Cu")
		(at 255.447546 -42.886122 90)
		(property "Reference" "PC2209"
			(at 0 0 90)
			(layer "F.SilkS")
			(hide yes)
			(effects
				(font
					(size 1.27 1.27)
				)
			)
		)
		(property "Value" ""
			(at 0 0 90)
			(layer "F.Fab")
			(effects
				(font
					(size 1.27 1.27)
				)
			)
		)
		(duplicate_pad_numbers_are_jumpers no)
		(fp_line
			(start 0.7874 -0.4064)
			(end 0.7874 0.4064)
			(stroke
				(width 0.1524)
				(type default)
			)
			(layer "F.SilkS")
		)
		(fp_line
			(start -0.7874 -0.4064)
			(end 0.7874 -0.4064)
			(stroke
				(width 0.1524)
				(type default)
			)
			(layer "F.SilkS")
		)
		(fp_line
			(start 0.7874 0.4064)
			(end -0.7874 0.4064)
			(stroke
				(width 0.1524)
				(type default)
			)
			(layer "F.SilkS")
		)
		(fp_line
			(start -0.7874 0.4064)
			(end -0.7874 -0.4064)
			(stroke
				(width 0.1524)
				(type default)
			)
			(layer "F.SilkS")
		)
		(fp_line
			(start -0.12065 -0.305054)
			(end -0.12065 -0.2794)
			(stroke
				(width 0.1)
				(type default)
			)
			(layer "F.Fab")
		)
		(fp_line
			(start -0.67945 -0.305054)
			(end -0.12065 -0.305054)
			(stroke
				(width 0.1)
				(type default)
			)
			(layer "F.Fab")
		)
		(fp_line
			(start 0.67945 -0.3048)
			(end 0.67945 0.3048)
			(stroke
				(width 0.1)
				(type default)
			)
			(layer "F.Fab")
		)
		(fp_line
			(start 0.12065 -0.3048)
			(end 0.67945 -0.3048)
			(stroke
				(width 0.1)
				(type default)
			)
			(layer "F.Fab")
		)
		(fp_line
			(start 0.12065 -0.2794)
			(end 0.12065 -0.3048)
			(stroke
				(width 0.1)
				(type default)
			)
			(layer "F.Fab")
		)
		(fp_line
			(start -0.12065 -0.2794)
			(end 0.12065 -0.2794)
			(stroke
				(width 0.1)
				(type default)
			)
			(layer "F.Fab")
		)
		(fp_line
			(start 0.120396 0.2794)
			(end -0.12065 0.2794)
			(stroke
				(width 0.1)
				(type default)
			)
			(layer "F.Fab")
		)
		(fp_line
			(start -0.12065 0.2794)
			(end -0.12065 0.3048)
			(stroke
				(width 0.1)
				(type default)
			)
			(layer "F.Fab")
		)
		(fp_line
			(start 0.67945 0.3048)
			(end 0.120396 0.3048)
			(stroke
				(width 0.1)
				(type default)
			)
			(layer "F.Fab")
		)
		(fp_line
			(start 0.120396 0.3048)
			(end 0.120396 0.2794)
			(stroke
				(width 0.1)
				(type default)
			)
			(layer "F.Fab")
		)
		(fp_line
			(start -0.12065 0.3048)
			(end -0.67945 0.3048)
			(stroke
				(width 0.1)
				(type default)
			)
			(layer "F.Fab")
		)
		(fp_line
			(start -0.67945 0.3048)
			(end -0.67945 -0.305054)
			(stroke
				(width 0.1)
				(type default)
			)
			(layer "F.Fab")
		)
		(pad "1" smd circle
			(at -0.40005 0 90)
			(size 0 0)
			(layers "F.Cu" "F.Mask" "F.Paste")
			(net "P12V_E1S_VCC_0")
		)
		(pad "2" smd circle
			(at 0.40005 0 90)
			(size 0 0)
			(layers "F.Cu" "F.Mask" "F.Paste")
			(net "GND")
		)
	)
)
